(kicad_pcb
	(version 20260206)
	(generator "pcbnew")
	(generator_version "10.0")
	(general
		(thickness 1.6)
		(legacy_teardrops no)
	)
	(paper "A4")
	(title_block
		(title "04192023_DAF0TMB3IC0_F0TG_MB_C_brd_V02_OCP.brd")
		(comment 1 "Grand Teton / footprints 1450-1455 of 8354")
	)
	(layers
		(0 "F.Cu" signal "TOP")
		(4 "In1.Cu" signal "GND")
		(6 "In2.Cu" signal "IN1")
		(8 "In3.Cu" signal "GND1")
		(10 "In4.Cu" signal "IN2")
		(12 "In5.Cu" signal "GND2")
		(14 "In6.Cu" signal "IN3")
		(16 "In7.Cu" signal "GND3")
		(18 "In8.Cu" signal "VCC")
		(20 "In9.Cu" signal "VCC1")
		(22 "In10.Cu" signal "GND4")
		(24 "In11.Cu" signal "IN4")
		(26 "In12.Cu" signal "GND5")
		(28 "In13.Cu" signal "IN5")
		(30 "In14.Cu" signal "GND6")
		(32 "In15.Cu" signal "IN6")
		(34 "In16.Cu" signal "GND7")
		(2 "B.Cu" signal "BOTTOM")
		(9 "F.Adhes" user "F.Adhesive")
		(11 "B.Adhes" user "B.Adhesive")
		(13 "F.Paste" user "Package Geometry/Pastemask Top")
		(15 "B.Paste" user "Package Geometry/Pastemask Bottom")
		(5 "F.SilkS" user "Ref Des/Silkscreen Top")
		(7 "B.SilkS" user "Ref Des/Silkscreen Bottom")
		(1 "F.Mask" user "Board Geometry/Soldermask Top")
		(3 "B.Mask" user "Board Geometry/Soldermask Bottom")
		(17 "Dwgs.User" user "User.Drawings")
		(19 "Cmts.User" user "User.Comments")
		(21 "Eco1.User" user "User.Eco1")
		(23 "Eco2.User" user "User.Eco2")
		(25 "Edge.Cuts" user "Board Geometry/Outline")
		(27 "Margin" user)
		(31 "F.CrtYd" user "Package Geometry/Place Bound Top")
		(29 "B.CrtYd" user "Package Geometry/Place Bound Bottom")
		(35 "F.Fab" user "Ref Des/Assembly Top")
		(33 "B.Fab" user "Ref Des/Assembly Bottom")
	)
	(footprint ""
		(layer "F.Cu")
		(at 212.725 -99.822)
		(property "Reference" "R9032"
			(at 0 0 0)
			(layer "F.SilkS")
			(hide yes)
			(effects
				(font
					(size 1.27 1.27)
				)
			)
		)
		(property "Value" ""
			(at 0 0 0)
			(layer "F.Fab")
			(effects
				(font
					(size 1.27 1.27)
				)
			)
		)
		(duplicate_pad_numbers_are_jumpers no)
		(fp_line
			(start -0.7874 -0.4064)
			(end 0.7874 -0.4064)
			(stroke
				(width 0.1524)
				(type default)
			)
			(layer "F.SilkS")
		)
		(fp_line
			(start -0.7874 0.4064)
			(end -0.7874 -0.4064)
			(stroke
				(width 0.1524)
				(type default)
			)
			(layer "F.SilkS")
		)
		(fp_line
			(start 0.7874 -0.4064)
			(end 0.7874 0.4064)
			(stroke
				(width 0.1524)
				(type default)
			)
			(layer "F.SilkS")
		)
		(fp_line
			(start 0.7874 0.4064)
			(end -0.7874 0.4064)
			(stroke
				(width 0.1524)
				(type default)
			)
			(layer "F.SilkS")
		)
		(fp_line
			(start -0.67945 -0.305054)
			(end -0.12065 -0.305054)
			(stroke
				(width 0.1)
				(type default)
			)
			(layer "F.Fab")
		)
		(fp_line
			(start -0.67945 0.3048)
			(end -0.67945 -0.305054)
			(stroke
				(width 0.1)
				(type default)
			)
			(layer "F.Fab")
		)
		(fp_line
			(start -0.12065 -0.305054)
			(end -0.12065 -0.2794)
			(stroke
				(width 0.1)
				(type default)
			)
			(layer "F.Fab")
		)
		(fp_line
			(start -0.12065 -0.2794)
			(end 0.12065 -0.2794)
			(stroke
				(width 0.1)
				(type default)
			)
			(layer "F.Fab")
		)
		(fp_line
			(start -0.12065 0.2794)
			(end -0.12065 0.3048)
			(stroke
				(width 0.1)
				(type default)
			)
			(layer "F.Fab")
		)
		(fp_line
			(start -0.12065 0.3048)
			(end -0.67945 0.3048)
			(stroke
				(width 0.1)
				(type default)
			)
			(layer "F.Fab")
		)
		(fp_line
			(start 0.120396 0.2794)
			(end -0.12065 0.2794)
			(stroke
				(width 0.1)
				(type default)
			)
			(layer "F.Fab")
		)
		(fp_line
			(start 0.120396 0.3048)
			(end 0.120396 0.2794)
			(stroke
				(width 0.1)
				(type default)
			)
			(layer "F.Fab")
		)
		(fp_line
			(start 0.12065 -0.3048)
			(end 0.67945 -0.3048)
			(stroke
				(width 0.1)
				(type default)
			)
			(layer "F.Fab")
		)
		(fp_line
			(start 0.12065 -0.2794)
			(end 0.12065 -0.3048)
			(stroke
				(width 0.1)
				(type default)
			)
			(layer "F.Fab")
		)
		(fp_line
			(start 0.67945 -0.3048)
			(end 0.67945 0.3048)
			(stroke
				(width 0.1)
				(type default)
			)
			(layer "F.Fab")
		)
		(fp_line
			(start 0.67945 0.3048)
			(end 0.120396 0.3048)
			(stroke
				(width 0.1)
				(type default)
			)
			(layer "F.Fab")
		)
		(pad "1" smd circle
			(at -0.40005 0)
			(size 0 0)
			(layers "F.Cu" "F.Mask" "F.Paste")
			(net "P3V3_AUX")
		)
		(pad "2" smd circle
			(at 0.40005 0)
			(size 0 0)
			(layers "F.Cu" "F.Mask" "F.Paste")
			(net "FM_PLD_OCP_SFF_AUX_PWR_EN")
		)
	)
	(footprint ""
		(layer "F.Cu")
		(at 372.937278 -139.440158)
		(property "Reference" "R8311"
			(at 0 0 0)
			(layer "F.SilkS")
			(hide yes)
			(effects
				(font
					(size 1.27 1.27)
				)
			)
		)
		(property "Value" ""
			(at 0 0 0)
			(layer "F.Fab")
			(effects
				(font
					(size 1.27 1.27)
				)
			)
		)
		(duplicate_pad_numbers_are_jumpers no)
		(fp_line
			(start -0.7874 -0.4064)
			(end 0.7874 -0.4064)
			(stroke
				(width 0.1524)
				(type default)
			)
			(layer "F.SilkS")
		)
		(fp_line
			(start -0.7874 0.4064)
			(end -0.7874 -0.4064)
			(stroke
				(width 0.1524)
				(type default)
			)
			(layer "F.SilkS")
		)
		(fp_line
			(start 0.7874 -0.4064)
			(end 0.7874 0.4064)
			(stroke
				(width 0.1524)
				(type default)
			)
			(layer "F.SilkS")
		)
		(fp_line
			(start 0.7874 0.4064)
			(end -0.7874 0.4064)
			(stroke
				(width 0.1524)
				(type default)
			)
			(layer "F.SilkS")
		)
		(fp_line
			(start -0.67945 -0.305054)
			(end -0.12065 -0.305054)
			(stroke
				(width 0.1)
				(type default)
			)
			(layer "F.Fab")
		)
		(fp_line
			(start -0.67945 0.3048)
			(end -0.67945 -0.305054)
			(stroke
				(width 0.1)
				(type default)
			)
			(layer "F.Fab")
		)
		(fp_line
			(start -0.12065 -0.305054)
			(end -0.12065 -0.2794)
			(stroke
				(width 0.1)
				(type default)
			)
			(layer "F.Fab")
		)
		(fp_line
			(start -0.12065 -0.2794)
			(end 0.12065 -0.2794)
			(stroke
				(width 0.1)
				(type default)
			)
			(layer "F.Fab")
		)
		(fp_line
			(start -0.12065 0.2794)
			(end -0.12065 0.3048)
			(stroke
				(width 0.1)
				(type default)
			)
			(layer "F.Fab")
		)
		(fp_line
			(start -0.12065 0.3048)
			(end -0.67945 0.3048)
			(stroke
				(width 0.1)
				(type default)
			)
			(layer "F.Fab")
		)
		(fp_line
			(start 0.120396 0.2794)
			(end -0.12065 0.2794)
			(stroke
				(width 0.1)
				(type default)
			)
			(layer "F.Fab")
		)
		(fp_line
			(start 0.120396 0.3048)
			(end 0.120396 0.2794)
			(stroke
				(width 0.1)
				(type default)
			)
			(layer "F.Fab")
		)
		(fp_line
			(start 0.12065 -0.3048)
			(end 0.67945 -0.3048)
			(stroke
				(width 0.1)
				(type default)
			)
			(layer "F.Fab")
		)
		(fp_line
			(start 0.12065 -0.2794)
			(end 0.12065 -0.3048)
			(stroke
				(width 0.1)
				(type default)
			)
			(layer "F.Fab")
		)
		(fp_line
			(start 0.67945 -0.3048)
			(end 0.67945 0.3048)
			(stroke
				(width 0.1)
				(type default)
			)
			(layer "F.Fab")
		)
		(fp_line
			(start 0.67945 0.3048)
			(end 0.120396 0.3048)
			(stroke
				(width 0.1)
				(type default)
			)
			(layer "F.Fab")
		)
		(pad "1" smd circle
			(at -0.40005 0)
			(size 0 0)
			(layers "F.Cu" "F.Mask" "F.Paste")
			(net "PWRGD_PVDDCR_CPU0_P0")
		)
		(pad "2" smd circle
			(at 0.40005 0)
			(size 0 0)
			(layers "F.Cu" "F.Mask" "F.Paste")
			(net "PWRGD_PVDDCR_CPU0_P0_R")
		)
	)
	(footprint ""
		(layer "F.Cu")
		(at 419.868096 -357.688134 -90)
		(property "Reference" "PR33"
			(at 0 0 270)
			(layer "F.SilkS")
			(hide yes)
			(effects
				(font
					(size 1.27 1.27)
				)
			)
		)
		(property "Value" ""
			(at 0 0 270)
			(layer "F.Fab")
			(effects
				(font
					(size 1.27 1.27)
				)
			)
		)
		(duplicate_pad_numbers_are_jumpers no)
		(fp_line
			(start -0.7874 0.4064)
			(end -0.7874 -0.4064)
			(stroke
				(width 0.1524)
				(type default)
			)
			(layer "F.SilkS")
		)
		(fp_line
			(start 0.7874 0.4064)
			(end -0.7874 0.4064)
			(stroke
				(width 0.1524)
				(type default)
			)
			(layer "F.SilkS")
		)
		(fp_line
			(start -0.7874 -0.4064)
			(end 0.7874 -0.4064)
			(stroke
				(width 0.1524)
				(type default)
			)
			(layer "F.SilkS")
		)
		(fp_line
			(start 0.7874 -0.4064)
			(end 0.7874 0.4064)
			(stroke
				(width 0.1524)
				(type default)
			)
			(layer "F.SilkS")
		)
		(fp_line
			(start -0.67945 0.3048)
			(end -0.67945 -0.305054)
			(stroke
				(width 0.1)
				(type default)
			)
			(layer "F.Fab")
		)
		(fp_line
			(start -0.12065 0.3048)
			(end -0.67945 0.3048)
			(stroke
				(width 0.1)
				(type default)
			)
			(layer "F.Fab")
		)
		(fp_line
			(start 0.120396 0.3048)
			(end 0.120396 0.2794)
			(stroke
				(width 0.1)
				(type default)
			)
			(layer "F.Fab")
		)
		(fp_line
			(start 0.67945 0.3048)
			(end 0.120396 0.3048)
			(stroke
				(width 0.1)
				(type default)
			)
			(layer "F.Fab")
		)
		(fp_line
			(start -0.12065 0.2794)
			(end -0.12065 0.3048)
			(stroke
				(width 0.1)
				(type default)
			)
			(layer "F.Fab")
		)
		(fp_line
			(start 0.120396 0.2794)
			(end -0.12065 0.2794)
			(stroke
				(width 0.1)
				(type default)
			)
			(layer "F.Fab")
		)
		(fp_line
			(start -0.12065 -0.2794)
			(end 0.12065 -0.2794)
			(stroke
				(width 0.1)
				(type default)
			)
			(layer "F.Fab")
		)
		(fp_line
			(start 0.12065 -0.2794)
			(end 0.12065 -0.3048)
			(stroke
				(width 0.1)
				(type default)
			)
			(layer "F.Fab")
		)
		(fp_line
			(start 0.12065 -0.3048)
			(end 0.67945 -0.3048)
			(stroke
				(width 0.1)
				(type default)
			)
			(layer "F.Fab")
		)
		(fp_line
			(start 0.67945 -0.3048)
			(end 0.67945 0.3048)
			(stroke
				(width 0.1)
				(type default)
			)
			(layer "F.Fab")
		)
		(fp_line
			(start -0.67945 -0.305054)
			(end -0.12065 -0.305054)
			(stroke
				(width 0.1)
				(type default)
			)
			(layer "F.Fab")
		)
		(fp_line
			(start -0.12065 -0.305054)
			(end -0.12065 -0.2794)
			(stroke
				(width 0.1)
				(type default)
			)
			(layer "F.Fab")
		)
		(pad "1" smd circle
			(at -0.40005 0 270)
			(size 0 0)
			(layers "F.Cu" "F.Mask" "F.Paste")
			(net "NC_PVDD11_S3_P0_IMON4")
		)
		(pad "2" smd circle
			(at 0.40005 0 270)
			(size 0 0)
			(layers "F.Cu" "F.Mask" "F.Paste")
			(net "GND")
		)
	)
	(footprint ""
		(layer "F.Cu")
		(at 41.874694 -17.623536 90)
		(property "Reference" "C697"
			(at 0 0 90)
			(layer "F.SilkS")
			(hide yes)
			(effects
				(font
					(size 1.27 1.27)
				)
			)
		)
		(property "Value" ""
			(at 0 0 90)
			(layer "F.Fab")
			(effects
				(font
					(size 1.27 1.27)
				)
			)
		)
		(duplicate_pad_numbers_are_jumpers no)
		(fp_line
			(start 0.299974 -0.150114)
			(end 0.299974 0.150114)
			(stroke
				(width 0.1)
				(type default)
			)
			(layer "F.Fab")
		)
		(fp_line
			(start -0.299974 -0.150114)
			(end 0.299974 -0.150114)
			(stroke
				(width 0.1)
				(type default)
			)
			(layer "F.Fab")
		)
		(fp_line
			(start 0.299974 0.150114)
			(end -0.299974 0.150114)
			(stroke
				(width 0.1)
				(type default)
			)
			(layer "F.Fab")
		)
		(fp_line
			(start -0.299974 0.150114)
			(end -0.299974 -0.150114)
			(stroke
				(width 0.1)
				(type default)
			)
			(layer "F.Fab")
		)
		(pad "1" smd rect
			(at -0.2667 0 90)
			(size 0.3048 0.381)
			(layers "F.Cu" "F.Mask" "F.Paste")
			(net "P5E_CPU1_G1_TX_C_DP<6>")
		)
		(pad "2" smd rect
			(at 0.2667 0 90)
			(size 0.3048 0.381)
			(layers "F.Cu" "F.Mask" "F.Paste")
			(net "P5E_CPU1_G1_TX_DP<6>")
		)
	)
	(footprint ""
		(layer "F.Cu")
		(at 111.791496 -370.57203 -90)
		(property "Reference" "C1541"
			(at 0 0 270)
			(layer "F.SilkS")
			(hide yes)
			(effects
				(font
					(size 1.27 1.27)
				)
			)
		)
		(property "Value" ""
			(at 0 0 270)
			(layer "F.Fab")
			(effects
				(font
					(size 1.27 1.27)
				)
			)
		)
		(duplicate_pad_numbers_are_jumpers no)
		(fp_line
			(start -0.299974 0.150114)
			(end -0.299974 -0.150114)
			(stroke
				(width 0.1)
				(type default)
			)
			(layer "F.Fab")
		)
		(fp_line
			(start 0.299974 0.150114)
			(end -0.299974 0.150114)
			(stroke
				(width 0.1)
				(type default)
			)
			(layer "F.Fab")
		)
		(fp_line
			(start -0.299974 -0.150114)
			(end 0.299974 -0.150114)
			(stroke
				(width 0.1)
				(type default)
			)
			(layer "F.Fab")
		)
		(fp_line
			(start 0.299974 -0.150114)
			(end 0.299974 0.150114)
			(stroke
				(width 0.1)
				(type default)
			)
			(layer "F.Fab")
		)
		(pad "1" smd rect
			(at -0.2667 0 270)
			(size 0.3048 0.381)
			(layers "F.Cu" "F.Mask" "F.Paste")
			(net "P5E_CPU1_P3_TX_C_DP<3>")
		)
		(pad "2" smd rect
			(at 0.2667 0 270)
			(size 0.3048 0.381)
			(layers "F.Cu" "F.Mask" "F.Paste")
			(net "P5E_CPU1_P3_TX_DP<3>")
		)
	)
	(footprint ""
		(layer "F.Cu")
		(at 136.803638 -391.051288)
		(property "Reference" "R6902"
			(at 0 0 0)
			(layer "F.SilkS")
			(hide yes)
			(effects
				(font
					(size 1.27 1.27)
				)
			)
		)
		(property "Value" ""
			(at 0 0 0)
			(layer "F.Fab")
			(effects
				(font
					(size 1.27 1.27)
				)
			)
		)
		(duplicate_pad_numbers_are_jumpers no)
		(fp_line
			(start -0.32512 -0.175006)
			(end 0.32512 -0.175006)
			(stroke
				(width 0.1)
				(type default)
			)
			(layer "F.Fab")
		)
		(fp_line
			(start -0.32512 0.175006)
			(end -0.32512 -0.175006)
			(stroke
				(width 0.1)
				(type default)
			)
			(layer "F.Fab")
		)
		(fp_line
			(start 0.32512 -0.175006)
			(end 0.32512 0.175006)
			(stroke
				(width 0.1)
				(type default)
			)
			(layer "F.Fab")
		)
		(fp_line
			(start 0.32512 0.175006)
			(end -0.32512 0.175006)
			(stroke
				(width 0.1)
				(type default)
			)
			(layer "F.Fab")
		)
		(pad "1" smd rect
			(at -0.2667 0)
			(size 0.3048 0.381)
			(layers "F.Cu" "F.Mask" "F.Paste")
			(net "NCF_A1_CPU1_P3_GND")
		)
		(pad "2" smd rect
			(at 0.2667 0 180)
			(size 0.3048 0.381)
			(layers "F.Cu" "F.Mask" "F.Paste")
			(net "GND")
		)
	)
)
